(kicad_pcb
	(version 20260206)
	(generator "pcbnew")
	(generator_version "10.0")
	(general
		(thickness 1.6)
		(legacy_teardrops no)
	)
	(paper "A4")
	(title_block
		(title "03242023_DA0F0TMBIJ0_F0T_Motherboard_J_brd_V01_OCP.brd")
		(comment 1 "Grand Teton / footprints 3489-3491 of 6105")
	)
	(layers
		(0 "F.Cu" signal "TOP")
		(4 "In1.Cu" signal "GND")
		(6 "In2.Cu" signal "IN1")
		(8 "In3.Cu" signal "GND1")
		(10 "In4.Cu" signal "IN2")
		(12 "In5.Cu" signal "GND2")
		(14 "In6.Cu" signal "IN3")
		(16 "In7.Cu" signal "GND3")
		(18 "In8.Cu" signal "VCC")
		(20 "In9.Cu" signal "VCC1")
		(22 "In10.Cu" signal "GND4")
		(24 "In11.Cu" signal "IN4")
		(26 "In12.Cu" signal "GND5")
		(28 "In13.Cu" signal "IN5")
		(30 "In14.Cu" signal "GND6")
		(32 "In15.Cu" signal "IN6")
		(34 "In16.Cu" signal "GND7")
		(2 "B.Cu" signal "BOTTOM")
		(9 "F.Adhes" user "F.Adhesive")
		(11 "B.Adhes" user "B.Adhesive")
		(13 "F.Paste" user "Package Geometry/Pastemask Top")
		(15 "B.Paste" user "Package Geometry/Pastemask Bottom")
		(5 "F.SilkS" user "Ref Des/Silkscreen Top")
		(7 "B.SilkS" user "Ref Des/Silkscreen Bottom")
		(1 "F.Mask" user "Board Geometry/Soldermask Top")
		(3 "B.Mask" user "Board Geometry/Soldermask Bottom")
		(17 "Dwgs.User" user "User.Drawings")
		(19 "Cmts.User" user "User.Comments")
		(21 "Eco1.User" user "User.Eco1")
		(23 "Eco2.User" user "User.Eco2")
		(25 "Edge.Cuts" user "Board Geometry/Outline")
		(27 "Margin" user)
		(31 "F.CrtYd" user "Package Geometry/Place Bound Top")
		(29 "B.CrtYd" user "Package Geometry/Place Bound Bottom")
		(35 "F.Fab" user "Ref Des/Assembly Top")
		(33 "B.Fab" user "Ref Des/Assembly Bottom")
	)
	(footprint ""
		(layer "F.Cu")
		(at 17.899888 -51.999896)
		(property "Reference" "J100"
			(at -2.413 -12.080748 0)
			(unlocked yes)
			(layer "F.SilkS")
			(effects
				(font
					(size 0.7874 0.5842)
					(thickness 0.1524)
				)
			)
		)
		(property "Value" ""
			(at 0 0 0)
			(layer "F.Fab")
			(effects
				(font
					(size 1.27 1.27)
				)
			)
		)
		(duplicate_pad_numbers_are_jumpers no)
		(fp_line
			(start -3.150108 -11.325098)
			(end 3.150108 -11.325098)
			(stroke
				(width 0.1524)
				(type default)
			)
			(layer "F.SilkS")
		)
		(fp_line
			(start -3.150108 -9.596882)
			(end -3.150108 -11.325098)
			(stroke
				(width 0.1524)
				(type default)
			)
			(layer "F.SilkS")
		)
		(fp_line
			(start -3.150108 -7.596886)
			(end -3.150108 -8.403082)
			(stroke
				(width 0.1524)
				(type default)
			)
			(layer "F.SilkS")
		)
		(fp_line
			(start -3.150108 -5.59689)
			(end -3.150108 -6.403086)
			(stroke
				(width 0.1524)
				(type default)
			)
			(layer "F.SilkS")
		)
		(fp_line
			(start -3.150108 -3.596894)
			(end -3.150108 -4.40309)
			(stroke
				(width 0.1524)
				(type default)
			)
			(layer "F.SilkS")
		)
		(fp_line
			(start -3.150108 -1.596898)
			(end -3.150108 -2.403094)
			(stroke
				(width 0.1524)
				(type default)
			)
			(layer "F.SilkS")
		)
		(fp_line
			(start -3.150108 0.403098)
			(end -3.150108 -0.403098)
			(stroke
				(width 0.1524)
				(type default)
			)
			(layer "F.SilkS")
		)
		(fp_line
			(start -3.150108 2.403094)
			(end -3.150108 1.596898)
			(stroke
				(width 0.1524)
				(type default)
			)
			(layer "F.SilkS")
		)
		(fp_line
			(start -3.150108 4.40309)
			(end -3.150108 3.596894)
			(stroke
				(width 0.1524)
				(type default)
			)
			(layer "F.SilkS")
		)
		(fp_line
			(start -3.150108 6.403086)
			(end -3.150108 5.59689)
			(stroke
				(width 0.1524)
				(type default)
			)
			(layer "F.SilkS")
		)
		(fp_line
			(start -3.150108 8.403082)
			(end -3.150108 7.596886)
			(stroke
				(width 0.1524)
				(type default)
			)
			(layer "F.SilkS")
		)
		(fp_line
			(start -3.150108 11.325098)
			(end -3.150108 9.596882)
			(stroke
				(width 0.1524)
				(type default)
			)
			(layer "F.SilkS")
		)
		(fp_line
			(start 3.150108 -11.325098)
			(end 3.150108 -9.596882)
			(stroke
				(width 0.1524)
				(type default)
			)
			(layer "F.SilkS")
		)
		(fp_line
			(start 3.150108 -8.403082)
			(end 3.150108 -7.596886)
			(stroke
				(width 0.1524)
				(type default)
			)
			(layer "F.SilkS")
		)
		(fp_line
			(start 3.150108 -6.403086)
			(end 3.150108 -5.59689)
			(stroke
				(width 0.1524)
				(type default)
			)
			(layer "F.SilkS")
		)
		(fp_line
			(start 3.150108 -4.40309)
			(end 3.150108 -3.596894)
			(stroke
				(width 0.1524)
				(type default)
			)
			(layer "F.SilkS")
		)
		(fp_line
			(start 3.150108 -2.403094)
			(end 3.150108 -1.596898)
			(stroke
				(width 0.1524)
				(type default)
			)
			(layer "F.SilkS")
		)
		(fp_line
			(start 3.150108 -0.403098)
			(end 3.150108 0.403098)
			(stroke
				(width 0.1524)
				(type default)
			)
			(layer "F.SilkS")
		)
		(fp_line
			(start 3.150108 1.596898)
			(end 3.150108 2.403094)
			(stroke
				(width 0.1524)
				(type default)
			)
			(layer "F.SilkS")
		)
		(fp_line
			(start 3.150108 3.596894)
			(end 3.150108 4.40309)
			(stroke
				(width 0.1524)
				(type default)
			)
			(layer "F.SilkS")
		)
		(fp_line
			(start 3.150108 5.59689)
			(end 3.150108 6.403086)
			(stroke
				(width 0.1524)
				(type default)
			)
			(layer "F.SilkS")
		)
		(fp_line
			(start 3.150108 7.596886)
			(end 3.150108 8.403082)
			(stroke
				(width 0.1524)
				(type default)
			)
			(layer "F.SilkS")
		)
		(fp_line
			(start 3.150108 9.596882)
			(end 3.150108 11.325098)
			(stroke
				(width 0.1524)
				(type default)
			)
			(layer "F.SilkS")
		)
		(fp_line
			(start 3.150108 11.325098)
			(end -3.150108 11.325098)
			(stroke
				(width 0.1524)
				(type default)
			)
			(layer "F.SilkS")
		)
		(fp_rect
			(start -3.150108 0.491998)
			(end -2.249932 -0.491998)
			(stroke
				(width 0)
				(type default)
			)
			(fill yes)
			(layer "F.SilkS")
		)
		(fp_poly
			(pts
				(xy -4.967224 -9.487662) (xy -3.951224 -8.979662) (xy -4.967224 -8.471662)
			)
			(stroke
				(width 0)
				(type default)
			)
			(fill yes)
			(layer "F.SilkS")
		)
		(fp_line
			(start -3.150108 -11.325098)
			(end 3.150108 -11.325098)
			(stroke
				(width 0.1)
				(type default)
			)
			(layer "F.Fab")
		)
		(fp_line
			(start -3.150108 11.325098)
			(end -3.150108 -11.325098)
			(stroke
				(width 0.1)
				(type default)
			)
			(layer "F.Fab")
		)
		(fp_line
			(start 3.150108 -11.325098)
			(end 3.150108 11.325098)
			(stroke
				(width 0.1)
				(type default)
			)
			(layer "F.Fab")
		)
		(fp_line
			(start 3.150108 11.325098)
			(end -3.150108 11.325098)
			(stroke
				(width 0.1)
				(type default)
			)
			(layer "F.Fab")
		)
		(fp_poly
			(pts
				(xy -4.728464 -9.507982) (xy -4.728464 -8.491982) (xy -3.712464 -8.999982)
			)
			(stroke
				(width 0)
				(type default)
			)
			(fill yes)
			(layer "F.Fab")
		)
		(pad "" np_thru_hole circle
			(at 0 -7.999984 270)
			(size 1.016 1.016)
			(drill 1.016)
			(layers "*.Cu" "*.Mask")
			(clearance 0.381)
			(thermal_gap 0.381)
		)
		(pad "" np_thru_hole circle
			(at 0 7.999984 270)
			(size 1.016 1.016)
			(drill 1.016)
			(layers "*.Cu" "*.Mask")
			(clearance 0.381)
			(thermal_gap 0.381)
		)
		(pad "1" smd rect
			(at -2.124964 -8.999982 270)
			(size 0.9144 2.7686)
			(layers "F.Cu" "F.Mask" "F.Paste")
			(net "SMB_SML0_ME_SCL")
		)
		(pad "2" smd rect
			(at 2.124964 -8.999982 270)
			(size 0.9144 2.7686)
			(layers "F.Cu" "F.Mask" "F.Paste")
			(net "GND")
		)
		(pad "3" smd rect
			(at -2.124964 -6.999986 270)
			(size 0.9144 2.7686)
			(layers "F.Cu" "F.Mask" "F.Paste")
			(net "SMB_SML0_ME_SDA")
		)
		(pad "4" smd rect
			(at 2.124964 -6.999986 270)
			(size 0.9144 2.7686)
			(layers "F.Cu" "F.Mask" "F.Paste")
			(net "IRQ_SML0_ALERT_R1_N")
		)
		(pad "5" smd rect
			(at -2.124964 -4.99999 270)
			(size 0.9144 2.7686)
			(layers "F.Cu" "F.Mask" "F.Paste")
			(net "SMB_PMBUS_SML1_ME_SCL")
		)
		(pad "6" smd rect
			(at 2.124964 -4.99999 270)
			(size 0.9144 2.7686)
			(layers "F.Cu" "F.Mask" "F.Paste")
			(net "GND")
		)
		(pad "7" smd rect
			(at -2.124964 -2.999994 270)
			(size 0.9144 2.7686)
			(layers "F.Cu" "F.Mask" "F.Paste")
			(net "SMB_PMBUS_SML1_ME_SDA")
		)
		(pad "8" smd rect
			(at 2.124964 -2.999994 270)
			(size 0.9144 2.7686)
			(layers "F.Cu" "F.Mask" "F.Paste")
			(net "IRQ_SML1_PMBUS_ALERT_R_N")
		)
		(pad "9" smd rect
			(at -2.124964 -0.999998 270)
			(size 0.9144 2.7686)
			(layers "F.Cu" "F.Mask" "F.Paste")
			(net "RST_RSMRST_NM_HDR_N")
		)
		(pad "10" smd rect
			(at 2.124964 -0.999998 270)
			(size 0.9144 2.7686)
			(layers "F.Cu" "F.Mask" "F.Paste")
			(net "GND")
		)
		(pad "11" smd rect
			(at -2.124964 0.999998 270)
			(size 0.9144 2.7686)
			(layers "F.Cu" "F.Mask" "F.Paste")
			(net "SMB_HOST_ME_SCL")
		)
		(pad "12" smd rect
			(at 2.124964 0.999998 270)
			(size 0.9144 2.7686)
			(layers "F.Cu" "F.Mask" "F.Paste")
			(net "GND")
		)
		(pad "13" smd rect
			(at -2.124964 2.999994 270)
			(size 0.9144 2.7686)
			(layers "F.Cu" "F.Mask" "F.Paste")
			(net "SMB_HOST_ME_SDA")
		)
		(pad "14" smd rect
			(at 2.124964 2.999994 270)
			(size 0.9144 2.7686)
			(layers "F.Cu" "F.Mask" "F.Paste")
			(net "Net_8591")
		)
		(pad "15" smd rect
			(at -2.124964 4.99999 270)
			(size 0.9144 2.7686)
			(layers "F.Cu" "F.Mask" "F.Paste")
			(net "GND")
		)
		(pad "16" smd rect
			(at 2.124964 4.99999 270)
			(size 0.9144 2.7686)
			(layers "F.Cu" "F.Mask" "F.Paste")
			(net "PECI_BMC_ME")
		)
		(pad "17" smd rect
			(at -2.124964 6.999986 270)
			(size 0.9144 2.7686)
			(layers "F.Cu" "F.Mask" "F.Paste")
			(net "GND")
		)
		(pad "18" smd rect
			(at 2.124964 6.999986 270)
			(size 0.9144 2.7686)
			(layers "F.Cu" "F.Mask" "F.Paste")
			(net "PWRGD_PS_PWROK_ME_CONN")
		)
		(pad "19" smd rect
			(at -2.124964 8.999982 270)
			(size 0.9144 2.7686)
			(layers "F.Cu" "F.Mask" "F.Paste")
			(net "FM_BIOS_POST_CMPLT_HDR_N")
		)
		(pad "20" smd rect
			(at 2.124964 8.999982 270)
			(size 0.9144 2.7686)
			(layers "F.Cu" "F.Mask" "F.Paste")
			(net "Net_8590")
		)
		(zone
			(layers "F.Cu" "B.Cu" "In1.Cu" "In2.Cu" "In3.Cu" "In4.Cu" "In5.Cu" "In6.Cu"
				"In7.Cu" "In8.Cu" "In9.Cu" "In10.Cu" "In11.Cu" "In12.Cu" "In13.Cu" "In14.Cu"
				"In15.Cu" "In16.Cu"
			)
			(hatch none 0.5)
			(connect_pads
				(clearance 0)
			)
			(min_thickness 0.25)
			(keepout
				(tracks not_allowed)
				(vias allowed)
				(pads allowed)
				(copperpour not_allowed)
				(footprints allowed)
			)
			(placement
				(enabled no)
				(sheetname "")
			)
			(fill
				(thermal_gap 0.5)
				(thermal_bridge_width 0.5)
				(island_removal_mode 0)
			)
			(polygon
				(pts
					(arc
						(start 18.814288 -59.99988)
						(mid 16.985488 -59.99988)
						(end 18.814288 -59.99988)
					)
				)
			)
		)
		(zone
			(layers "F.Cu" "B.Cu" "In1.Cu" "In2.Cu" "In3.Cu" "In4.Cu" "In5.Cu" "In6.Cu"
				"In7.Cu" "In8.Cu" "In9.Cu" "In10.Cu" "In11.Cu" "In12.Cu" "In13.Cu" "In14.Cu"
				"In15.Cu" "In16.Cu"
			)
			(hatch none 0.5)
			(connect_pads
				(clearance 0)
			)
			(min_thickness 0.25)
			(keepout
				(tracks not_allowed)
				(vias allowed)
				(pads allowed)
				(copperpour not_allowed)
				(footprints allowed)
			)
			(placement
				(enabled no)
				(sheetname "")
			)
			(fill
				(thermal_gap 0.5)
				(thermal_bridge_width 0.5)
				(island_removal_mode 0)
			)
			(polygon
				(pts
					(arc
						(start 18.814288 -43.999912)
						(mid 16.985488 -43.999912)
						(end 18.814288 -43.999912)
					)
				)
			)
		)
	)
	(footprint ""
		(layer "F.Cu")
		(at 369.81511 -409.6512)
		(property "Reference" "R4739"
			(at 0 0 0)
			(layer "F.SilkS")
			(hide yes)
			(effects
				(font
					(size 1.27 1.27)
				)
			)
		)
		(property "Value" ""
			(at 0 0 0)
			(layer "F.Fab")
			(effects
				(font
					(size 1.27 1.27)
				)
			)
		)
		(duplicate_pad_numbers_are_jumpers no)
		(fp_line
			(start -0.7874 -0.4064)
			(end 0.7874 -0.4064)
			(stroke
				(width 0.1524)
				(type default)
			)
			(layer "F.SilkS")
		)
		(fp_line
			(start -0.7874 0.4064)
			(end -0.7874 -0.4064)
			(stroke
				(width 0.1524)
				(type default)
			)
			(layer "F.SilkS")
		)
		(fp_line
			(start 0.7874 -0.4064)
			(end 0.7874 0.4064)
			(stroke
				(width 0.1524)
				(type default)
			)
			(layer "F.SilkS")
		)
		(fp_line
			(start 0.7874 0.4064)
			(end -0.7874 0.4064)
			(stroke
				(width 0.1524)
				(type default)
			)
			(layer "F.SilkS")
		)
		(fp_line
			(start -0.67945 -0.305054)
			(end -0.12065 -0.305054)
			(stroke
				(width 0.1)
				(type default)
			)
			(layer "F.Fab")
		)
		(fp_line
			(start -0.67945 0.3048)
			(end -0.67945 -0.305054)
			(stroke
				(width 0.1)
				(type default)
			)
			(layer "F.Fab")
		)
		(fp_line
			(start -0.12065 -0.305054)
			(end -0.12065 -0.2794)
			(stroke
				(width 0.1)
				(type default)
			)
			(layer "F.Fab")
		)
		(fp_line
			(start -0.12065 -0.2794)
			(end 0.12065 -0.2794)
			(stroke
				(width 0.1)
				(type default)
			)
			(layer "F.Fab")
		)
		(fp_line
			(start -0.12065 0.2794)
			(end -0.12065 0.3048)
			(stroke
				(width 0.1)
				(type default)
			)
			(layer "F.Fab")
		)
		(fp_line
			(start -0.12065 0.3048)
			(end -0.67945 0.3048)
			(stroke
				(width 0.1)
				(type default)
			)
			(layer "F.Fab")
		)
		(fp_line
			(start 0.120396 0.2794)
			(end -0.12065 0.2794)
			(stroke
				(width 0.1)
				(type default)
			)
			(layer "F.Fab")
		)
		(fp_line
			(start 0.120396 0.3048)
			(end 0.120396 0.2794)
			(stroke
				(width 0.1)
				(type default)
			)
			(layer "F.Fab")
		)
		(fp_line
			(start 0.12065 -0.3048)
			(end 0.67945 -0.3048)
			(stroke
				(width 0.1)
				(type default)
			)
			(layer "F.Fab")
		)
		(fp_line
			(start 0.12065 -0.2794)
			(end 0.12065 -0.3048)
			(stroke
				(width 0.1)
				(type default)
			)
			(layer "F.Fab")
		)
		(fp_line
			(start 0.67945 -0.3048)
			(end 0.67945 0.3048)
			(stroke
				(width 0.1)
				(type default)
			)
			(layer "F.Fab")
		)
		(fp_line
			(start 0.67945 0.3048)
			(end 0.120396 0.3048)
			(stroke
				(width 0.1)
				(type default)
			)
			(layer "F.Fab")
		)
		(pad "1" smd circle
			(at -0.40005 0)
			(size 0 0)
			(layers "F.Cu" "F.Mask" "F.Paste")
			(net "P3V3_AUX")
		)
		(pad "2" smd circle
			(at 0.40005 0)
			(size 0 0)
			(layers "F.Cu" "F.Mask" "F.Paste")
			(net "PRSNT_CABLE_SWB_B1")
		)
	)
	(footprint ""
		(layer "F.Cu")
		(at 39.032688 -439.198512 180)
		(property "Reference" "U200"
			(at 0.153416 -2.198878 0)
			(unlocked yes)
			(layer "F.SilkS")
			(effects
				(font
					(size 0.7874 0.5842)
					(thickness 0.1524)
				)
				(justify left)
			)
		)
		(property "Value" ""
			(at 0 0 180)
			(layer "F.Fab")
			(effects
				(font
					(size 1.27 1.27)
				)
			)
		)
		(duplicate_pad_numbers_are_jumpers no)
		(fp_line
			(start 1.3716 1.524)
			(end -1.3716 1.524)
			(stroke
				(width 0.1524)
				(type default)
			)
			(layer "F.SilkS")
		)
		(fp_line
			(start 1.3716 -1.524)
			(end 1.3716 1.524)
			(stroke
				(width 0.1524)
				(type default)
			)
			(layer "F.SilkS")
		)
		(fp_line
			(start 0.508 -1.524)
			(end 1.3716 -1.524)
			(stroke
				(width 0.1524)
				(type default)
			)
			(layer "F.SilkS")
		)
		(fp_line
			(start 0 -1.016)
			(end 0.508 -1.524)
			(stroke
				(width 0.1524)
				(type default)
			)
			(layer "F.SilkS")
		)
		(fp_line
			(start -0.508 -1.524)
			(end 0 -1.016)
			(stroke
				(width 0.1524)
				(type default)
			)
			(layer "F.SilkS")
		)
		(fp_line
			(start -1.3716 1.524)
			(end -1.3716 -1.524)
			(stroke
				(width 0.1524)
				(type default)
			)
			(layer "F.SilkS")
		)
		(fp_line
			(start -1.3716 -1.524)
			(end -0.508 -1.524)
			(stroke
				(width 0.1524)
				(type default)
			)
			(layer "F.SilkS")
		)
		(fp_poly
			(pts
				(xy -3.70332 -1.270508) (xy -3.1496 -0.94234) (xy -3.70332 -0.645668)
			)
			(stroke
				(width 0)
				(type default)
			)
			(fill yes)
			(layer "F.SilkS")
		)
		(fp_line
			(start 2.54 1.0668)
			(end 1.5494 1.0668)
			(stroke
				(width 0.1)
				(type default)
			)
			(layer "F.Fab")
		)
		(fp_line
			(start 2.54 -1.0668)
			(end 2.54 1.0668)
			(stroke
				(width 0.1)
				(type default)
			)
			(layer "F.Fab")
		)
		(fp_line
			(start 1.5494 1.524)
			(end -1.5494 1.524)
			(stroke
				(width 0.1)
				(type default)
			)
			(layer "F.Fab")
		)
		(fp_line
			(start 1.5494 1.0668)
			(end 1.5494 1.524)
			(stroke
				(width 0.1)
				(type default)
			)
			(layer "F.Fab")
		)
		(fp_line
			(start 1.5494 -1.0668)
			(end 2.54 -1.0668)
			(stroke
				(width 0.1)
				(type default)
			)
			(layer "F.Fab")
		)
		(fp_line
			(start 1.5494 -1.0668)
			(end 1.5494 1.0668)
			(stroke
				(width 0.1)
				(type default)
			)
			(layer "F.Fab")
		)
		(fp_line
			(start 1.5494 -1.524)
			(end 1.5494 -1.0668)
			(stroke
				(width 0.1)
				(type default)
			)
			(layer "F.Fab")
		)
		(fp_line
			(start -1.5494 1.524)
			(end -1.5494 1.0668)
			(stroke
				(width 0.1)
				(type default)
			)
			(layer "F.Fab")
		)
		(fp_line
			(start -1.5494 1.0668)
			(end -1.5494 -1.0668)
			(stroke
				(width 0.1)
				(type default)
			)
			(layer "F.Fab")
		)
		(fp_line
			(start -1.5494 1.0668)
			(end -2.54 1.0668)
			(stroke
				(width 0.1)
				(type default)
			)
			(layer "F.Fab")
		)
		(fp_line
			(start -1.5494 -1.0668)
			(end -1.5494 -1.524)
			(stroke
				(width 0.1)
				(type default)
			)
			(layer "F.Fab")
		)
		(fp_line
			(start -1.5494 -1.524)
			(end 1.5494 -1.524)
			(stroke
				(width 0.1)
				(type default)
			)
			(layer "F.Fab")
		)
		(fp_line
			(start -2.54 1.0668)
			(end -2.54 -1.0668)
			(stroke
				(width 0.1)
				(type default)
			)
			(layer "F.Fab")
		)
		(fp_line
			(start -2.54 -1.0668)
			(end -1.5494 -1.0668)
			(stroke
				(width 0.1)
				(type default)
			)
			(layer "F.Fab")
		)
		(fp_poly
			(pts
				(xy -3.60172 -0.719328) (xy -3.60172 -1.344168) (xy -3.048 -1.016)
			)
			(stroke
				(width 0)
				(type default)
			)
			(fill yes)
			(layer "F.Fab")
		)
		(pad "1" smd rect
			(at -2.232406 -0.975106 90)
			(size 0.3556 1.4224)
			(layers "F.Cu" "F.Mask" "F.Paste")
			(net "SMB_BMC_GPU_EN_R3")
		)
		(pad "2" smd rect
			(at -2.232406 -0.32512 90)
			(size 0.3556 1.4224)
			(layers "F.Cu" "F.Mask" "F.Paste")
			(net "SMB_2_BMC_GPU_BUF_R_SCL")
		)
		(pad "3" smd rect
			(at -2.232406 0.32512 90)
			(size 0.3556 1.4224)
			(layers "F.Cu" "F.Mask" "F.Paste")
			(net "SMB_2_BMC_GPU_R_SCL")
		)
		(pad "4" smd rect
			(at -2.232406 0.975106 90)
			(size 0.3556 1.4224)
			(layers "F.Cu" "F.Mask" "F.Paste")
			(net "GND")
		)
		(pad "5" smd rect
			(at 2.232406 0.975106 90)
			(size 0.3556 1.4224)
			(layers "F.Cu" "F.Mask" "F.Paste")
			(net "Net_1937")
		)
		(pad "6" smd rect
			(at 2.232406 0.32512 90)
			(size 0.3556 1.4224)
			(layers "F.Cu" "F.Mask" "F.Paste")
			(net "SMB_2_BMC_GPU_R_SDA")
		)
		(pad "7" smd rect
			(at 2.232406 -0.32512 90)
			(size 0.3556 1.4224)
			(layers "F.Cu" "F.Mask" "F.Paste")
			(net "SMB_2_BMC_GPU_BUF_R_SDA")
		)
		(pad "8" smd rect
			(at 2.232406 -0.975106 90)
			(size 0.3556 1.4224)
			(layers "F.Cu" "F.Mask" "F.Paste")
			(net "P3V3_AUX")
		)
	)
)
